# S9S_MB_2U (Grand Teton) — schematic netlist excerpt (pin names and nets, part order shuffled) for the footprints in the layout excerpt that follows; sources: Cadence DE-HDL packaged netlist, KiCad conversion of 03242023_DA0F0TMBIJ0_F0T_Motherboard_J_brd_V01_OCP.brd

J9  SCONN288_ADR50017P130CC  SCONN288_ADR50017-P130CC IO  pkg DDR288S_1-1VXB  page 90
  VIN_BULK0  = P12V_S3_AUX_CPU0_NVDIMM
  RFU0  = TP_CHE_CPU0_DIMM1_FRU_0
  VIN_MGMT  = P3V3_AUX
  HSCL  = I3C_SPD_DDREFGH_CPU0_LVC1_SCL_R
  HSDA  = I3C_SPD_DDREFGH_CPU0_LVC1_SDA
  VSS0  = GND
  DQ0_A  = M_E_CPU0_SA_DQ<0>
  VSS1  = GND
  DQ1_A  = M_E_CPU0_SA_DQ<1>
  VSS2  = GND
  DQS0_A_T  = M_E_CPU0_SA_DQS_DP<0>
  DQS0_A_C  = M_E_CPU0_SA_DQS_DN<0>
  VSS3  = GND
  DQ4_A  = M_E_CPU0_SA_DQ<4>
  VSS4  = GND
  DQ5_A  = M_E_CPU0_SA_DQ<5>
  VSS5  = GND
  DQ8_A  = M_E_CPU0_SA_DQ<8>
  VSS6  = GND
  DQ9_A  = M_E_CPU0_SA_DQ<9>
  VSS7  = GND
  DQS1_A_T  = M_E_CPU0_SA_DQS_DP<1>
  DQS1_A_C  = M_E_CPU0_SA_DQS_DN<1>
  VSS8  = GND
  DQ12_A  = M_E_CPU0_SA_DQ<12>
  VSS9  = GND
  DQ13_A  = M_E_CPU0_SA_DQ<13>
  VSS10  = GND
  DQ16_A  = M_E_CPU0_SA_DQ<16>
  VSS11  = GND
  DQ17_A  = M_E_CPU0_SA_DQ<17>
  VSS12  = GND
  DQS2_A_T  = M_E_CPU0_SA_DQS_DP<2>
  DQS2_A_C  = M_E_CPU0_SA_DQS_DN<2>
  VSS13  = GND
  DQ20_A  = M_E_CPU0_SA_DQ<20>
  VSS14  = GND
  DQ21_A  = M_E_CPU0_SA_DQ<21>
  VSS15  = GND
  DQ24_A  = M_E_CPU0_SA_DQ<24>
  VSS16  = GND
  DQ25_A  = M_E_CPU0_SA_DQ<25>
  VSS17  = GND
  DQS3_A_T  = M_E_CPU0_SA_DQS_DP<3>
  DQS3_A_C  = M_E_CPU0_SA_DQS_DN<3>
  VSS18  = GND
  DQ28_A  = M_E_CPU0_SA_DQ<28>
  VSS19  = GND
  DQ29_A  = M_E_CPU0_SA_DQ<29>
  VSS20  = GND
  CB0_A  = M_E_CPU0_SA_CB<0>
  VSS21  = GND
  CB1_A  = M_E_CPU0_SA_CB<1>
  VSS22  = GND
  DQS4_A_T  = M_E_CPU0_SA_DQS_DP<4>
  DQS4_A_C  = M_E_CPU0_SA_DQS_DN<4>
  VSS23  = GND
  CB4_A  = M_E_CPU0_SA_CB<4>
  VSS24  = GND
  CB5_A  = M_E_CPU0_SA_CB<5>
  VSS25  = GND
  ALERT_N  = M_E_CPU0_ALERT_N
  VSS26  = GND
  CS0_A_N  = M_E_CPU0_SA_CS_N<0>
  VSS27  = GND
  CA0_A  = M_E_CPU0_SA_CA<0>
  VSS28  = GND
  CA2_A  = M_E_CPU0_SA_CA<2>
  VSS29  = GND
  CA4_A  = M_E_CPU0_SA_CA<4>
  VSS30  = GND
  CA6_A  = M_E_CPU0_SA_CA<6>
  VSS31  = GND
  PAR_A  = M_E_CPU0_SA_PAR
  VSS32  = GND
  CA0_B  = M_E_CPU0_SB_CA<0>
  VSS33  = GND
  CA2_B  = M_E_CPU0_SB_CA<2>
  VSS34  = GND
  CA4_B  = M_E_CPU0_SB_CA<4>
  VSS35  = GND
  CA6_B  = M_E_CPU0_SB_CA<6>
  VSS36  = GND
  CS0_B_N  = M_E_CPU0_SB_CS_N<0>
  VSS37  = GND
  \lbd||rsp_a_n\  = M_E_CPU0_SA_RSP<0>
  \lbs||rsp_b_n\  = M_E_CPU0_SB_RSP<0>
  VSS38  = GND
  CB4_B  = M_E_CPU0_SB_CB<4>
  VSS39  = GND
  CB5_B  = M_E_CPU0_SB_CB<5>
  VSS40  = GND
  \dqs9_b_t||tdqs9_b_t||dbi4_b_n\  = M_E_CPU0_SB_DQS_DP<9>
  \dqs9_b_c||tdqs9_b_c\  = M_E_CPU0_SB_DQS_DN<9>
  VSS41  = GND
  CB0_B  = M_E_CPU0_SB_CB<0>
  VSS42  = GND
  CB1_B  = M_E_CPU0_SB_CB<1>
  VSS43  = GND
  DQ0_B  = M_E_CPU0_SB_DQ<0>
  VSS44  = GND
  DQ1_B  = M_E_CPU0_SB_DQ<1>
  VSS45  = GND
  DQS0_B_T  = M_E_CPU0_SB_DQS_DP<0>
  DQS0_B_C  = M_E_CPU0_SB_DQS_DN<0>
  VSS46  = GND
  DQ4_B  = M_E_CPU0_SB_DQ<4>
  VSS47  = GND
  DQ5_B  = M_E_CPU0_SB_DQ<5>
  VSS48  = GND
  DQ8_B  = M_E_CPU0_SB_DQ<8>
  VSS49  = GND
  DQ9_B  = M_E_CPU0_SB_DQ<9>
  VSS50  = GND
  DQS1_B_T  = M_E_CPU0_SB_DQS_DP<1>
  DQS1_B_C  = M_E_CPU0_SB_DQS_DN<1>
  VSS51  = GND
  DQ12_B  = M_E_CPU0_SB_DQ<12>
  VSS52  = GND
  DQ13_B  = M_E_CPU0_SB_DQ<13>
  VSS53  = GND
  DQ16_B  = M_E_CPU0_SB_DQ<16>
  VSS54  = GND
  DQ17_B  = M_E_CPU0_SB_DQ<17>
  VSS55  = GND
  DQS2_B_T  = M_E_CPU0_SB_DQS_DP<2>
  DQS2_B_C  = M_E_CPU0_SB_DQS_DN<2>
  VSS56  = GND
  DQ20_B  = M_E_CPU0_SB_DQ<20>
  VSS57  = GND
  DQ21_B  = M_E_CPU0_SB_DQ<21>
  VSS58  = GND
  DQ24_B  = M_E_CPU0_SB_DQ<24>
  VSS59  = GND
  DQ25_B  = M_E_CPU0_SB_DQ<25>
  VSS60  = GND
  DQS3_B_T  = M_E_CPU0_SB_DQS_DP<3>
  DQS3_B_C  = M_E_CPU0_SB_DQS_DN<3>
  VSS61  = GND
  DQ28_B  = M_E_CPU0_SB_DQ<28>
  VSS62  = GND
  DQ29_B  = M_E_CPU0_SB_DQ<29>
  VSS63  = GND
  RFU1  = TP_CHE_CPU0_DIMM1_FRU_1
  VIN_BULK1  = P12V_S3_AUX_CPU0_NVDIMM
  VIN_BULK2  = P12V_S3_AUX_CPU0_NVDIMM
  \pwr_good||fail_n\  = PWRGD_CHE_CPU0_DIMM1
  HSA  = PD_CHE_CPU0_DIMM1_SAA
  RFU2  = TP_CHE_CPU0_DIMM1_FRU_2
  RFU3  = TP_CHE_CPU0_DIMM1_FRU_3
  VSS64  = GND
  DQ2_A  = M_E_CPU0_SA_DQ<2>
  VSS65  = GND
  DQ3_A  = M_E_CPU0_SA_DQ<3>
  VSS66  = GND
  \dqs5_a_c||tdqs5_a_c||dqs5_a_t||tdqs5_a_t\  = M_E_CPU0_SA_DQS_DN<5>
  \dqs5_a_t||tdqs5_a_t\  = M_E_CPU0_SA_DQS_DP<5>
  VSS67  = GND
  DQ6_A  = M_E_CPU0_SA_DQ<6>
  VSS68  = GND
  DQ7_A  = M_E_CPU0_SA_DQ<7>
  VSS69  = GND
  DQ10_A  = M_E_CPU0_SA_DQ<10>
  VSS70  = GND
  DQ11_A  = M_E_CPU0_SA_DQ<11>
  VSS71  = GND
  \dqs6_a_c||tdqs6_a_c||dqs6_a_t||tdqs6_a_t\  = M_E_CPU0_SA_DQS_DN<6>
  \dqs6_a_t||tdqs6_a_t\  = M_E_CPU0_SA_DQS_DP<6>
  VSS72  = GND
  DQ14_A  = M_E_CPU0_SA_DQ<14>
  VSS73  = GND
  DQ15_A  = M_E_CPU0_SA_DQ<15>
  VSS74  = GND
  DQ18_A  = M_E_CPU0_SA_DQ<18>
  VSS75  = GND
  DQ19_A  = M_E_CPU0_SA_DQ<19>
  VSS76  = GND
  \dqs7_a_c||tdqs7_a_c\  = M_E_CPU0_SA_DQS_DN<7>
  \dqs7_a_t||tdqs7_a_t\  = M_E_CPU0_SA_DQS_DP<7>
  VSS77  = GND
  DQ22_A  = M_E_CPU0_SA_DQ<22>
  VSS78  = GND
  DQ23_A  = M_E_CPU0_SA_DQ<23>
  VSS79  = GND
  DQ26_A  = M_E_CPU0_SA_DQ<26>
  VSS80  = GND
  DQ27_A  = M_E_CPU0_SA_DQ<27>
  VSS81  = GND
  \dqs8_a_c||tdqs8_a_c\  = M_E_CPU0_SA_DQS_DN<8>
  \dqs8_a_t||tdqs8_a_t\  = M_E_CPU0_SA_DQS_DP<8>
  VSS82  = GND
  DQ30_A  = M_E_CPU0_SA_DQ<30>
  VSS83  = GND
  DQ31_A  = M_E_CPU0_SA_DQ<31>
  VSS84  = GND
  CB2_A  = M_E_CPU0_SA_CB<2>
  VSS85  = GND
  CB3_A  = M_E_CPU0_SA_CB<3>
  VSS86  = GND
  \dqs9_a_c||tdqs9_a_c\  = M_E_CPU0_SA_DQS_DN<9>
  \dqs9_a_t||tdqs9_a_t\  = M_E_CPU0_SA_DQS_DP<9>
  VSS87  = GND
  CB6_A  = M_E_CPU0_SA_CB<6>
  VSS88  = GND
  CB7_A  = M_E_CPU0_SA_CB<7>
  VSS89  = GND
  RESET_N  = RST_M_EF_CPU0_FPGA_N
  VSS90  = GND
  CS1_A_N  = M_E_CPU0_SA_CS_N<1>
  VSS91  = GND
  CA1_A  = M_E_CPU0_SA_CA<1>
  VSS92  = GND
  CA3_A  = M_E_CPU0_SA_CA<3>
  VSS93  = GND
  CA5_A  = M_E_CPU0_SA_CA<5>
  VSS94  = GND
  CK_T  = M_E_CPU0_CLK_DP<0>
  CK_C  = M_E_CPU0_CLK_DN<0>
  VSS95  = GND
  RFU4  = TP_CHE_CPU0_DIMM1_FRU_4
  CA1_B  = M_E_CPU0_SB_CA<1>
  VSS96  = GND
  CA3_B  = M_E_CPU0_SB_CA<3>
  VSS97  = GND
  CA5_B  = M_E_CPU0_SB_CA<5>
  VSS98  = GND
  PAR_B  = M_E_CPU0_SB_PAR
  VSS99  = GND
  CS1_B_N  = M_E_CPU0_SB_CS_N<1>
  VSS100  = GND
  RFU5  = TP_CHE_CPU0_DIMM1_FRU_5
  RFU6  = TP_CHE_CPU0_DIMM1_FRU_6
  VSS101  = GND
  CB6_B  = M_E_CPU0_SB_CB<6>
  VSS102  = GND
  CB7_B  = M_E_CPU0_SB_CB<7>
  VSS103  = GND
  DQS4_B_C  = M_E_CPU0_SB_DQS_DN<4>
  DQS4_B_T  = M_E_CPU0_SB_DQS_DP<4>
  VSS104  = GND
  CB2_B  = M_E_CPU0_SB_CB<2>
  VSS105  = GND
  CB3_B  = M_E_CPU0_SB_CB<3>
  VSS106  = GND
  DQ2_B  = M_E_CPU0_SB_DQ<2>
  VSS107  = GND
  DQ3_B  = M_E_CPU0_SB_DQ<3>
  VSS108  = GND
  \dqs5_b_c||tdqs5_b_c\  = M_E_CPU0_SB_DQS_DN<5>
  \dqs5_b_t||tdqs5_b_t\  = M_E_CPU0_SB_DQS_DP<5>
  VSS109  = GND
  DQ6_B  = M_E_CPU0_SB_DQ<6>
  VSS110  = GND
  DQ7_B  = M_E_CPU0_SB_DQ<7>
  VSS111  = GND
  DQ10_B  = M_E_CPU0_SB_DQ<10>
  VSS112  = GND
  DQ11_B  = M_E_CPU0_SB_DQ<11>
  VSS113  = GND
  \dqs6_b_c||tdqs6_b_c\  = M_E_CPU0_SB_DQS_DN<6>
  \dqs6_b_t||tdqs6_b_t\  = M_E_CPU0_SB_DQS_DP<6>
  VSS114  = GND
  DQ14_B  = M_E_CPU0_SB_DQ<14>
  VSS115  = GND
  DQ15_B  = M_E_CPU0_SB_DQ<15>
  VSS116  = GND
  DQ18_B  = M_E_CPU0_SB_DQ<18>
  VSS117  = GND
  DQ19_B  = M_E_CPU0_SB_DQ<19>
  VSS118  = GND
  \dqs7_b_c||tdqs7_b_c\  = M_E_CPU0_SB_DQS_DN<7>
  \dqs7_b_t||tdqs7_b_t\  = M_E_CPU0_SB_DQS_DP<7>
  VSS119  = GND
  DQ22_B  = M_E_CPU0_SB_DQ<22>
  VSS120  = GND
  DQ23_B  = M_E_CPU0_SB_DQ<23>
  VSS121  = GND
  DQ26_B  = M_E_CPU0_SB_DQ<26>
  VSS122  = GND
  DQ27_B  = M_E_CPU0_SB_DQ<27>
  VSS123  = GND
  \dqs8_b_c||tdqs8_b_c\  = M_E_CPU0_SB_DQS_DN<8>
  \dqs8_b_t||tdqs8_b_t\  = M_E_CPU0_SB_DQS_DP<8>
  VSS124  = GND
  DQ30_B  = M_E_CPU0_SB_DQ<30>
  VSS125  = GND
  DQ31_B  = M_E_CPU0_SB_DQ<31>
  VSS126  = GND
  G1  = GND
  G2  = GND
  G3  = GND

(kicad_pcb
	(version 20260206)
	(generator "pcbnew")
	(generator_version "10.0")
	(general
		(thickness 1.6)
		(legacy_teardrops no)
	)
	(paper "A4")
	(title_block
		(title "03242023_DA0F0TMBIJ0_F0T_Motherboard_J_brd_V01_OCP.brd")
		(comment 1 "Grand Teton / footprint 461 of 6105 (J9), pads 275-291 of 291")
	)
	(layers
		(0 "F.Cu" signal "TOP")
		(4 "In1.Cu" signal "GND")
		(6 "In2.Cu" signal "IN1")
		(8 "In3.Cu" signal "GND1")
		(10 "In4.Cu" signal "IN2")
		(12 "In5.Cu" signal "GND2")
		(14 "In6.Cu" signal "IN3")
		(16 "In7.Cu" signal "GND3")
		(18 "In8.Cu" signal "VCC")
		(20 "In9.Cu" signal "VCC1")
		(22 "In10.Cu" signal "GND4")
		(24 "In11.Cu" signal "IN4")
		(26 "In12.Cu" signal "GND5")
		(28 "In13.Cu" signal "IN5")
		(30 "In14.Cu" signal "GND6")
		(32 "In15.Cu" signal "IN6")
		(34 "In16.Cu" signal "GND7")
		(2 "B.Cu" signal "BOTTOM")
		(9 "F.Adhes" user "F.Adhesive")
		(11 "B.Adhes" user "B.Adhesive")
		(13 "F.Paste" user "Package Geometry/Pastemask Top")
		(15 "B.Paste" user "Package Geometry/Pastemask Bottom")
		(5 "F.SilkS" user "Ref Des/Silkscreen Top")
		(7 "B.SilkS" user "Ref Des/Silkscreen Bottom")
		(1 "F.Mask" user "Board Geometry/Soldermask Top")
		(3 "B.Mask" user "Board Geometry/Soldermask Bottom")
		(17 "Dwgs.User" user "User.Drawings")
		(19 "Cmts.User" user "User.Comments")
		(21 "Eco1.User" user "User.Eco1")
		(23 "Eco2.User" user "User.Eco2")
		(25 "Edge.Cuts" user "Board Geometry/Outline")
		(27 "Margin" user)
		(31 "F.CrtYd" user "Package Geometry/Place Bound Top")
		(29 "B.CrtYd" user "Package Geometry/Place Bound Bottom")
		(35 "F.Fab" user "Ref Des/Assembly Top")
		(33 "B.Fab" user "Ref Des/Assembly Bottom")
	)
	(footprint ""
		(layer "F.Cu")
		(at 416.347148 -258.091686)
		(property "Reference" "J9"
			(at -3.683 -81.702148 0)
			(unlocked yes)
			(layer "F.SilkS")
			(effects
				(font
					(size 0.7874 0.5842)
					(thickness 0.1524)
				)
				(justify left)
			)
		)
		(property "Value" ""
			(at 0 0 0)
			(layer "F.Fab")
			(effects
				(font
					(size 1.27 1.27)
				)
			)
		)
		(duplicate_pad_numbers_are_jumpers no)
		(pad "275" smd rect
			(at 2.050034 52.274978 270)
			(size 0.519938 1.4986)
			(layers "F.Cu" "F.Mask" "F.Paste")
			(net "GND")
		)
		(pad "276" smd rect
			(at 2.050034 53.125116 270)
			(size 0.519938 1.4986)
			(layers "F.Cu" "F.Mask" "F.Paste")
			(net "M_E_CPU0_SB_DQ<23>")
		)
		(pad "277" smd rect
			(at 2.050034 53.975 270)
			(size 0.519938 1.4986)
			(layers "F.Cu" "F.Mask" "F.Paste")
			(net "GND")
		)
		(pad "278" smd rect
			(at 2.050034 54.824884 270)
			(size 0.519938 1.4986)
			(layers "F.Cu" "F.Mask" "F.Paste")
			(net "M_E_CPU0_SB_DQ<26>")
		)
		(pad "279" smd rect
			(at 2.050034 55.675022 270)
			(size 0.519938 1.4986)
			(layers "F.Cu" "F.Mask" "F.Paste")
			(net "GND")
		)
		(pad "280" smd rect
			(at 2.050034 56.524906 270)
			(size 0.519938 1.4986)
			(layers "F.Cu" "F.Mask" "F.Paste")
			(net "M_E_CPU0_SB_DQ<27>")
		)
		(pad "281" smd rect
			(at 2.050034 57.375044 270)
			(size 0.519938 1.4986)
			(layers "F.Cu" "F.Mask" "F.Paste")
			(net "GND")
		)
		(pad "282" smd rect
			(at 2.050034 58.224928 270)
			(size 0.519938 1.4986)
			(layers "F.Cu" "F.Mask" "F.Paste")
			(net "M_E_CPU0_SB_DQS_DN<8>")
		)
		(pad "283" smd rect
			(at 2.050034 59.075066 270)
			(size 0.519938 1.4986)
			(layers "F.Cu" "F.Mask" "F.Paste")
			(net "M_E_CPU0_SB_DQS_DP<8>")
		)
		(pad "284" smd rect
			(at 2.050034 59.92495 270)
			(size 0.519938 1.4986)
			(layers "F.Cu" "F.Mask" "F.Paste")
			(net "GND")
		)
		(pad "285" smd rect
			(at 2.050034 60.775088 270)
			(size 0.519938 1.4986)
			(layers "F.Cu" "F.Mask" "F.Paste")
			(net "M_E_CPU0_SB_DQ<30>")
		)
		(pad "286" smd rect
			(at 2.050034 61.624972 270)
			(size 0.519938 1.4986)
			(layers "F.Cu" "F.Mask" "F.Paste")
			(net "GND")
		)
		(pad "287" smd rect
			(at 2.050034 62.47511 270)
			(size 0.519938 1.4986)
			(layers "F.Cu" "F.Mask" "F.Paste")
			(net "M_E_CPU0_SB_DQ<31>")
		)
		(pad "288" smd rect
			(at 2.050034 63.324994 270)
			(size 0.519938 1.4986)
			(layers "F.Cu" "F.Mask" "F.Paste")
			(net "GND")
		)
		(pad "G1" thru_hole oval
			(at 0 -68.97497)
			(size 2.8194 1.5748)
			(drill oval 2.4384 1.1938)
			(layers "*.Cu" "*.Mask")
			(remove_unused_layers no)
			(net "GND")
			(clearance 0.127)
			(thermal_gap 0.127)
		)
		(pad "G2" thru_hole oval
			(at 0 3.875024)
			(size 2.8194 1.5748)
			(drill oval 2.4384 1.1938)
			(layers "*.Cu" "*.Mask")
			(remove_unused_layers no)
			(net "GND")
			(clearance 0.127)
			(thermal_gap 0.127)
		)
		(pad "G3" thru_hole oval
			(at 0 68.97497)
			(size 2.8194 1.5748)
			(drill oval 2.4384 1.1938)
			(layers "*.Cu" "*.Mask")
			(remove_unused_layers no)
			(net "GND")
			(clearance 0.127)
			(thermal_gap 0.127)
		)
	)
)
